# HONEY BADGER RISER CARD GCE-1A BOM of 81.B0710.042G_20150213.xlsx — Primary and Alternate BOM of 81 (bom)
| Level | Parent Number | Part Number | Description | Green Factor | Life Cycle State | Manufacturer | Manufacturer Part Number | Source | BOM Usage | M/P Code | S/D | Qty | UoM | Location |
| 1 | 81.B0710.042G | 40.58D03.001 | LBL POLYIMIDE31.8*6.35 BARCODE | R2_SA;HF_SA;G_SA; | Released | LABELJET | 40.58D03.001 | Single |  | Purchase |  | 2 | PCS |  |
| 1 | 81.B0710.042G | 55.B0711.D05G | HONEY BADGER RISER CARD GCE(D)-1A | N/A; | Released |  |  |  | E | Manufacture |  | 1 | PCS |  |
| 2 | 55.B0711.D05G | 20.50409.164 | CONN EDGE 164P AAA-PCI-006-G05 ,PA46 | R2_SA; | Released | LOTES | AAA-PCI-006-G05 | Single |  | Purchase | DIP | 1 | PCS | CN1 |
| 2 | 55.B0711.D05G | 55.B0711.S05G | HONEY BADGER RISER CARD GCE(S)-1A | N/A; | Released |  |  |  | E | Manufacture | DIP | 1 | PCS |  |
| 3 | 55.B0711.S05G | 48.B0722.01A | PCB 13919-1A HONEY BADGER RISER CD 4L GC | R2_C; | Released | GCE |  | Single |  | Purchase | SMT | 1 | PCS |  |
| 1 | 81.B0710.042G | DP.B0710.S06 | DP HONEY BADGER RISER CARD-SB | N/A; | Released |  |  |  | E | Manufacture |  | 1 | PCS |  |
| 2 | DP.B0710.S06 | 40.54T01.001 | LBL CAUTION FOR P97AE | R2_SA;G_SA; | Released | CHENGMAY | 40.54T01.001 | Single |  | Purchase |  | 1 | PCS |  |
| 2 | DP.B0710.S06 | 42.58U02.001 | ESD BAG 80*150*0.08MM | R2_SA; | Released | TBD |  | Single |  | Purchase |  | 1 | PCS |  |
| 2 | DP.B0710.S06 | 44.56F02.011 | CTN AB B/R 390*323*176MM | R2_SA; | Released | TRICAN | Void | Single |  | Purchase |  | 1.5879999999999998E-2 | PCS |  |
| 2 | DP.B0710.S06 | 45.00005.312 | LBL CTN ART 124*40 B/W ALL | R2_SA;G_SA; | Released | CHENGMAY | 45.00005.312 | Single |  | Purchase |  | 3.175E-2 | PCS |  |
| 2 | DP.B0710.S06 | 46.30S02.001 | CORNER KRAFT PAPER 900*50*50*3 | R2_SA;HF_SA;G_SA; | Released | KHL;SAFEWAY | 46.30S02.001 | Multiple |  | Purchase |  | 7.1000000000000002E-4 | PCS |  |
| 2 | DP.B0710.S06 | 46.30S14.001 | CORNER KRAFT PAPER 950*50*50*3 | R2_SA;HF_SA;G_SA; | Released | MYS;MOONSHINE | 46.30S14.001 | Multiple |  | Purchase |  | 1.42E-3 | PCS |  |
| 2 | DP.B0710.S06 | 46.58F01.001 | CORNER PAPER1100*50*50*3 ORIGI | R2_SA;G_SA; | Released | COPLASCO;MYS | 46.58F01.001 | Multiple |  | Purchase |  | 7.1000000000000002E-4 | PCS |  |
| 2 | DP.B0710.S06 | 46.60A03.001 | SHEET AB FLUTE 1200*1000 NS110 | R2_SA;G_SA; | Released | GINYOUNG;TRICAN | 46.60A03.001 | Multiple |  | Purchase |  | 3.6000000000000002E-4 | PCS |  |
| 2 | DP.B0710.S06 | 47.51I02.001 | PARTITION B 312*137MM | R2_SA; | Released | TRICAN | Void | Single |  | Purchase |  | 0.12698999999999999 | PCS |  |
| 2 | DP.B0710.S06 | 47.56F04.001 | PARTITION B 379*137MM | R2_SA; | Released | TRICAN | Void | Single |  | Purchase |  | 0.15873000000000001 | PCS |  |
| 2 | DP.B0710.S06 | 47.57S22.001 | PALLET PLYWOOD 1200*1000*114MM | R2_SA; | Released | JIAMAO | Void | Single |  | Purchase |  | 3.6000000000000002E-4 | PCS |  |
| 2 | DP.B0710.S06 | 47.5M604.001 | CSN PAD EPE 375*310*10MM | R2_SA; | Released | TBD |  | Single |  | Purchase |  | 3.175E-2 | PCS |  |
